# S9S_MB_2U (Grand Teton) — schematic netlist excerpt (pin names and nets, part order shuffled) for the footprints in the layout excerpt that follows; sources: Cadence DE-HDL packaged netlist, KiCad conversion of 03242023_DA0F0TMBIJ0_F0T_Motherboard_J_brd_V01_OCP.brd

U67  74CBTLV3126PW  IC  pkg TSSOP14  page 154
  \1oe\  = FB_BMC_ISOLATE
  \1a\  = NCSI_BMC_RXD1_R
  \1b\  = NCSI_OCP_SFF_RXD1
  \2oe\  = FB_BMC_ISOLATE
  \2a\  = NCSI_BMC_RXD0_R
  \2b\  = NCSI_OCP_SFF_RXD0
  GND  = GND
  \3b\  = NCSI_OCP_SFF_CRS_DV
  \3a\  = NCSI_BMC_CRS_DV_R
  \3oe\  = FB_BMC_ISOLATE
  \4b\  = OCP_SFF_ISO1_RBT_ARB_IN
  \4a\  = OCP_SFF_RBT_ARB_IN_R
  \4oe\  = FB_BMC_ISOLATE
  VCC  = P3V3_AUX

C516  Q_CAP  47UF 2.5V 20% X6S  pkg C0603  page 76 : A = PVCCFA_EHV_CPU0 ; B = GND

(kicad_pcb
	(version 20260206)
	(generator "pcbnew")
	(generator_version "10.0")
	(general
		(thickness 1.6)
		(legacy_teardrops no)
	)
	(paper "A4")
	(title_block
		(title "03242023_DA0F0TMBIJ0_F0T_Motherboard_J_brd_V01_OCP.brd")
		(comment 1 "Grand Teton / footprints 5249-5250 of 6105")
	)
	(layers
		(0 "F.Cu" signal "TOP")
		(4 "In1.Cu" signal "GND")
		(6 "In2.Cu" signal "IN1")
		(8 "In3.Cu" signal "GND1")
		(10 "In4.Cu" signal "IN2")
		(12 "In5.Cu" signal "GND2")
		(14 "In6.Cu" signal "IN3")
		(16 "In7.Cu" signal "GND3")
		(18 "In8.Cu" signal "VCC")
		(20 "In9.Cu" signal "VCC1")
		(22 "In10.Cu" signal "GND4")
		(24 "In11.Cu" signal "IN4")
		(26 "In12.Cu" signal "GND5")
		(28 "In13.Cu" signal "IN5")
		(30 "In14.Cu" signal "GND6")
		(32 "In15.Cu" signal "IN6")
		(34 "In16.Cu" signal "GND7")
		(2 "B.Cu" signal "BOTTOM")
		(9 "F.Adhes" user "F.Adhesive")
		(11 "B.Adhes" user "B.Adhesive")
		(13 "F.Paste" user "Package Geometry/Pastemask Top")
		(15 "B.Paste" user "Package Geometry/Pastemask Bottom")
		(5 "F.SilkS" user "Ref Des/Silkscreen Top")
		(7 "B.SilkS" user "Ref Des/Silkscreen Bottom")
		(1 "F.Mask" user "Board Geometry/Soldermask Top")
		(3 "B.Mask" user "Board Geometry/Soldermask Bottom")
		(17 "Dwgs.User" user "User.Drawings")
		(19 "Cmts.User" user "User.Comments")
		(21 "Eco1.User" user "User.Eco1")
		(23 "Eco2.User" user "User.Eco2")
		(25 "Edge.Cuts" user "Board Geometry/Outline")
		(27 "Margin" user)
		(31 "F.CrtYd" user "Package Geometry/Place Bound Top")
		(29 "B.CrtYd" user "Package Geometry/Place Bound Bottom")
		(35 "F.Fab" user "Ref Des/Assembly Top")
		(33 "B.Fab" user "Ref Des/Assembly Bottom")
	)
	(footprint ""
		(layer "B.Cu")
		(at 197.225158 -77.192632)
		(property "Reference" "U67"
			(at 2.032 -3.27533 0)
			(unlocked yes)
			(layer "B.SilkS")
			(effects
				(font
					(size 0.7874 0.5842)
					(thickness 0.1524)
				)
				(justify left mirror)
			)
		)
		(property "Value" ""
			(at 0 0 0)
			(layer "B.Fab")
			(effects
				(font
					(size 1.27 1.27)
				)
				(justify mirror)
			)
		)
		(duplicate_pad_numbers_are_jumpers no)
		(fp_line
			(start -2.0066 -2.5527)
			(end -2.0066 2.5527)
			(stroke
				(width 0.1524)
				(type default)
			)
			(layer "B.SilkS")
		)
		(fp_line
			(start -2.0066 2.5527)
			(end 2.0066 2.5527)
			(stroke
				(width 0.1524)
				(type default)
			)
			(layer "B.SilkS")
		)
		(fp_line
			(start -0.5715 -2.5527)
			(end -2.0066 -2.5527)
			(stroke
				(width 0.1524)
				(type default)
			)
			(layer "B.SilkS")
		)
		(fp_line
			(start 0 -1.9812)
			(end -0.5715 -2.5527)
			(stroke
				(width 0.1524)
				(type default)
			)
			(layer "B.SilkS")
		)
		(fp_line
			(start 0.5715 -2.5527)
			(end 0 -1.9812)
			(stroke
				(width 0.1524)
				(type default)
			)
			(layer "B.SilkS")
		)
		(fp_line
			(start 2.0066 -2.5527)
			(end 0.5715 -2.5527)
			(stroke
				(width 0.1524)
				(type default)
			)
			(layer "B.SilkS")
		)
		(fp_line
			(start 2.0066 2.5527)
			(end 2.0066 -2.5527)
			(stroke
				(width 0.1524)
				(type default)
			)
			(layer "B.SilkS")
		)
		(fp_poly
			(pts
				(xy 3.81 -1.905) (xy 4.36372 -2.233168) (xy 4.36372 -1.608328)
			)
			(stroke
				(width 0)
				(type default)
			)
			(fill yes)
			(layer "B.SilkS")
		)
		(fp_line
			(start -2.249932 -2.549906)
			(end -2.249932 2.549906)
			(stroke
				(width 0.1)
				(type default)
			)
			(layer "B.Fab")
		)
		(fp_line
			(start -2.249932 2.549906)
			(end 2.249932 2.549906)
			(stroke
				(width 0.1)
				(type default)
			)
			(layer "B.Fab")
		)
		(fp_line
			(start 2.249932 -2.549906)
			(end -2.249932 -2.549906)
			(stroke
				(width 0.1)
				(type default)
			)
			(layer "B.Fab")
		)
		(fp_line
			(start 2.249932 2.549906)
			(end 2.249932 -2.549906)
			(stroke
				(width 0.1)
				(type default)
			)
			(layer "B.Fab")
		)
		(fp_poly
			(pts
				(xy 4.36372 -1.608328) (xy 4.36372 -2.233168) (xy 3.81 -1.905)
			)
			(stroke
				(width 0)
				(type default)
			)
			(fill yes)
			(layer "B.Fab")
		)
		(pad "1" smd rect
			(at 2.921 -1.949958 270)
			(size 0.3556 1.4986)
			(layers "B.Cu" "B.Mask" "B.Paste")
			(net "FB_BMC_ISOLATE")
		)
		(pad "2" smd rect
			(at 2.921 -1.299972 270)
			(size 0.3556 1.4986)
			(layers "B.Cu" "B.Mask" "B.Paste")
			(net "NCSI_BMC_RXD1_R")
		)
		(pad "3" smd rect
			(at 2.921 -0.649986 270)
			(size 0.3556 1.4986)
			(layers "B.Cu" "B.Mask" "B.Paste")
			(net "NCSI_OCP_SFF_RXD1")
		)
		(pad "4" smd rect
			(at 2.921 0 270)
			(size 0.3556 1.4986)
			(layers "B.Cu" "B.Mask" "B.Paste")
			(net "FB_BMC_ISOLATE")
		)
		(pad "5" smd rect
			(at 2.921 0.649986 270)
			(size 0.3556 1.4986)
			(layers "B.Cu" "B.Mask" "B.Paste")
			(net "NCSI_BMC_RXD0_R")
		)
		(pad "6" smd rect
			(at 2.921 1.299972 270)
			(size 0.3556 1.4986)
			(layers "B.Cu" "B.Mask" "B.Paste")
			(net "NCSI_OCP_SFF_RXD0")
		)
		(pad "7" smd rect
			(at 2.921 1.949958 270)
			(size 0.3556 1.4986)
			(layers "B.Cu" "B.Mask" "B.Paste")
			(net "GND")
		)
		(pad "8" smd rect
			(at -2.921 1.949958 270)
			(size 0.3556 1.4986)
			(layers "B.Cu" "B.Mask" "B.Paste")
			(net "NCSI_OCP_SFF_CRS_DV")
		)
		(pad "9" smd rect
			(at -2.921 1.299972 270)
			(size 0.3556 1.4986)
			(layers "B.Cu" "B.Mask" "B.Paste")
			(net "NCSI_BMC_CRS_DV_R")
		)
		(pad "10" smd rect
			(at -2.921 0.649986 270)
			(size 0.3556 1.4986)
			(layers "B.Cu" "B.Mask" "B.Paste")
			(net "FB_BMC_ISOLATE")
		)
		(pad "11" smd rect
			(at -2.921 0 270)
			(size 0.3556 1.4986)
			(layers "B.Cu" "B.Mask" "B.Paste")
			(net "OCP_SFF_ISO1_RBT_ARB_IN")
		)
		(pad "12" smd rect
			(at -2.921 -0.649986 270)
			(size 0.3556 1.4986)
			(layers "B.Cu" "B.Mask" "B.Paste")
			(net "OCP_SFF_RBT_ARB_IN_R")
		)
		(pad "13" smd rect
			(at -2.921 -1.299972 270)
			(size 0.3556 1.4986)
			(layers "B.Cu" "B.Mask" "B.Paste")
			(net "FB_BMC_ISOLATE")
		)
		(pad "14" smd rect
			(at -2.921 -1.949958 270)
			(size 0.3556 1.4986)
			(layers "B.Cu" "B.Mask" "B.Paste")
			(net "P3V3_AUX")
		)
	)
	(footprint ""
		(layer "B.Cu")
		(at 349.344742 -210.41868 180)
		(property "Reference" "C516"
			(at 0 0 0)
			(layer "B.SilkS")
			(hide yes)
			(effects
				(font
					(size 1.27 1.27)
				)
				(justify mirror)
			)
		)
		(property "Value" ""
			(at 0 0 0)
			(layer "B.Fab")
			(effects
				(font
					(size 1.27 1.27)
				)
				(justify mirror)
			)
		)
		(duplicate_pad_numbers_are_jumpers no)
		(fp_line
			(start 1.2954 0.5842)
			(end 1.2954 -0.5842)
			(stroke
				(width 0.1524)
				(type default)
			)
			(layer "B.SilkS")
		)
		(fp_line
			(start 1.2954 -0.5842)
			(end -1.2954 -0.5842)
			(stroke
				(width 0.1524)
				(type default)
			)
			(layer "B.SilkS")
		)
		(fp_line
			(start 0 -0.5842)
			(end 0 0.5842)
			(stroke
				(width 0.1524)
				(type default)
			)
			(layer "B.SilkS")
		)
		(fp_line
			(start -1.2954 0.5842)
			(end 1.2954 0.5842)
			(stroke
				(width 0.1524)
				(type default)
			)
			(layer "B.SilkS")
		)
		(fp_line
			(start -1.2954 -0.5842)
			(end -1.2954 0.5842)
			(stroke
				(width 0.1524)
				(type default)
			)
			(layer "B.SilkS")
		)
		(fp_line
			(start 1.1938 0.4064)
			(end 1.1938 -0.4064)
			(stroke
				(width 0.1)
				(type default)
			)
			(layer "B.Fab")
		)
		(fp_line
			(start 1.1938 -0.4064)
			(end 0.8636 -0.4064)
			(stroke
				(width 0.1)
				(type default)
			)
			(layer "B.Fab")
		)
		(fp_line
			(start 0.8636 0.4572)
			(end 0.8636 0.4064)
			(stroke
				(width 0.1)
				(type default)
			)
			(layer "B.Fab")
		)
		(fp_line
			(start 0.8636 0.4064)
			(end 1.1938 0.4064)
			(stroke
				(width 0.1)
				(type default)
			)
			(layer "B.Fab")
		)
		(fp_line
			(start 0.8636 -0.4064)
			(end 0.8636 -0.4572)
			(stroke
				(width 0.1)
				(type default)
			)
			(layer "B.Fab")
		)
		(fp_line
			(start 0.8636 -0.4572)
			(end -0.8636 -0.4572)
			(stroke
				(width 0.1)
				(type default)
			)
			(layer "B.Fab")
		)
		(fp_line
			(start -0.8636 0.4572)
			(end 0.8636 0.4572)
			(stroke
				(width 0.1)
				(type default)
			)
			(layer "B.Fab")
		)
		(fp_line
			(start -0.8636 0.4064)
			(end -0.8636 0.4572)
			(stroke
				(width 0.1)
				(type default)
			)
			(layer "B.Fab")
		)
		(fp_line
			(start -0.8636 -0.4064)
			(end -1.1938 -0.4064)
			(stroke
				(width 0.1)
				(type default)
			)
			(layer "B.Fab")
		)
		(fp_line
			(start -0.8636 -0.4572)
			(end -0.8636 -0.4064)
			(stroke
				(width 0.1)
				(type default)
			)
			(layer "B.Fab")
		)
		(fp_line
			(start -1.1938 0.4064)
			(end -0.8636 0.4064)
			(stroke
				(width 0.1)
				(type default)
			)
			(layer "B.Fab")
		)
		(fp_line
			(start -1.1938 -0.4064)
			(end -1.1938 0.4064)
			(stroke
				(width 0.1)
				(type default)
			)
			(layer "B.Fab")
		)
		(pad "1" smd rect
			(at 0.7366 0 90)
			(size 0.7112 0.8128)
			(layers "B.Cu" "B.Mask" "B.Paste")
			(net "PVCCFA_EHV_CPU0")
		)
		(pad "2" smd rect
			(at -0.7366 0 90)
			(size 0.7112 0.8128)
			(layers "B.Cu" "B.Mask" "B.Paste")
			(net "GND")
		)
	)
)
